(kicad_pcb
	(version 20260206)
	(generator "pcbnew")
	(generator_version "10.0")
	(general
		(thickness 1.6)
		(legacy_teardrops no)
	)
	(paper "A4")
	(title_block
		(title "04192023_DAF0TMB3IC0_F0TG_MB_C_brd_V02_OCP.brd")
		(comment 1 "Grand Teton / footprints 1188-1194 of 8354")
	)
	(layers
		(0 "F.Cu" signal "TOP")
		(4 "In1.Cu" signal "GND")
		(6 "In2.Cu" signal "IN1")
		(8 "In3.Cu" signal "GND1")
		(10 "In4.Cu" signal "IN2")
		(12 "In5.Cu" signal "GND2")
		(14 "In6.Cu" signal "IN3")
		(16 "In7.Cu" signal "GND3")
		(18 "In8.Cu" signal "VCC")
		(20 "In9.Cu" signal "VCC1")
		(22 "In10.Cu" signal "GND4")
		(24 "In11.Cu" signal "IN4")
		(26 "In12.Cu" signal "GND5")
		(28 "In13.Cu" signal "IN5")
		(30 "In14.Cu" signal "GND6")
		(32 "In15.Cu" signal "IN6")
		(34 "In16.Cu" signal "GND7")
		(2 "B.Cu" signal "BOTTOM")
		(9 "F.Adhes" user "F.Adhesive")
		(11 "B.Adhes" user "B.Adhesive")
		(13 "F.Paste" user "Package Geometry/Pastemask Top")
		(15 "B.Paste" user "Package Geometry/Pastemask Bottom")
		(5 "F.SilkS" user "Ref Des/Silkscreen Top")
		(7 "B.SilkS" user "Ref Des/Silkscreen Bottom")
		(1 "F.Mask" user "Board Geometry/Soldermask Top")
		(3 "B.Mask" user "Board Geometry/Soldermask Bottom")
		(17 "Dwgs.User" user "User.Drawings")
		(19 "Cmts.User" user "User.Comments")
		(21 "Eco1.User" user "User.Eco1")
		(23 "Eco2.User" user "User.Eco2")
		(25 "Edge.Cuts" user "Board Geometry/Outline")
		(27 "Margin" user)
		(31 "F.CrtYd" user "Package Geometry/Place Bound Top")
		(29 "B.CrtYd" user "Package Geometry/Place Bound Bottom")
		(35 "F.Fab" user "Ref Des/Assembly Top")
		(33 "B.Fab" user "Ref Des/Assembly Bottom")
	)
	(footprint ""
		(layer "F.Cu")
		(at 223.393 -76.581 180)
		(property "Reference" "C8010"
			(at 0 0 180)
			(layer "F.SilkS")
			(hide yes)
			(effects
				(font
					(size 1.27 1.27)
				)
			)
		)
		(property "Value" ""
			(at 0 0 180)
			(layer "F.Fab")
			(effects
				(font
					(size 1.27 1.27)
				)
			)
		)
		(duplicate_pad_numbers_are_jumpers no)
		(fp_line
			(start 0.7874 0.4064)
			(end -0.7874 0.4064)
			(stroke
				(width 0.1524)
				(type default)
			)
			(layer "F.SilkS")
		)
		(fp_line
			(start 0.7874 -0.4064)
			(end 0.7874 0.4064)
			(stroke
				(width 0.1524)
				(type default)
			)
			(layer "F.SilkS")
		)
		(fp_line
			(start -0.7874 0.4064)
			(end -0.7874 -0.4064)
			(stroke
				(width 0.1524)
				(type default)
			)
			(layer "F.SilkS")
		)
		(fp_line
			(start -0.7874 -0.4064)
			(end 0.7874 -0.4064)
			(stroke
				(width 0.1524)
				(type default)
			)
			(layer "F.SilkS")
		)
		(fp_line
			(start 0.67945 0.3048)
			(end 0.120396 0.3048)
			(stroke
				(width 0.1)
				(type default)
			)
			(layer "F.Fab")
		)
		(fp_line
			(start 0.67945 -0.3048)
			(end 0.67945 0.3048)
			(stroke
				(width 0.1)
				(type default)
			)
			(layer "F.Fab")
		)
		(fp_line
			(start 0.12065 -0.2794)
			(end 0.12065 -0.3048)
			(stroke
				(width 0.1)
				(type default)
			)
			(layer "F.Fab")
		)
		(fp_line
			(start 0.12065 -0.3048)
			(end 0.67945 -0.3048)
			(stroke
				(width 0.1)
				(type default)
			)
			(layer "F.Fab")
		)
		(fp_line
			(start 0.120396 0.3048)
			(end 0.120396 0.2794)
			(stroke
				(width 0.1)
				(type default)
			)
			(layer "F.Fab")
		)
		(fp_line
			(start 0.120396 0.2794)
			(end -0.12065 0.2794)
			(stroke
				(width 0.1)
				(type default)
			)
			(layer "F.Fab")
		)
		(fp_line
			(start -0.12065 0.3048)
			(end -0.67945 0.3048)
			(stroke
				(width 0.1)
				(type default)
			)
			(layer "F.Fab")
		)
		(fp_line
			(start -0.12065 0.2794)
			(end -0.12065 0.3048)
			(stroke
				(width 0.1)
				(type default)
			)
			(layer "F.Fab")
		)
		(fp_line
			(start -0.12065 -0.2794)
			(end 0.12065 -0.2794)
			(stroke
				(width 0.1)
				(type default)
			)
			(layer "F.Fab")
		)
		(fp_line
			(start -0.12065 -0.305054)
			(end -0.12065 -0.2794)
			(stroke
				(width 0.1)
				(type default)
			)
			(layer "F.Fab")
		)
		(fp_line
			(start -0.67945 0.3048)
			(end -0.67945 -0.305054)
			(stroke
				(width 0.1)
				(type default)
			)
			(layer "F.Fab")
		)
		(fp_line
			(start -0.67945 -0.305054)
			(end -0.12065 -0.305054)
			(stroke
				(width 0.1)
				(type default)
			)
			(layer "F.Fab")
		)
		(pad "1" smd circle
			(at -0.40005 0 180)
			(size 0 0)
			(layers "F.Cu" "F.Mask" "F.Paste")
			(net "P3V3_E1S_0_R")
		)
		(pad "2" smd circle
			(at 0.40005 0 180)
			(size 0 0)
			(layers "F.Cu" "F.Mask" "F.Paste")
			(net "GND")
		)
	)
	(footprint ""
		(layer "F.Cu")
		(at 338.378546 -416.899344 -90)
		(property "Reference" "C6523"
			(at 0 0 270)
			(layer "F.SilkS")
			(hide yes)
			(effects
				(font
					(size 1.27 1.27)
				)
			)
		)
		(property "Value" ""
			(at 0 0 270)
			(layer "F.Fab")
			(effects
				(font
					(size 1.27 1.27)
				)
			)
		)
		(duplicate_pad_numbers_are_jumpers no)
		(fp_line
			(start -0.299974 0.150114)
			(end -0.299974 -0.150114)
			(stroke
				(width 0.1)
				(type default)
			)
			(layer "F.Fab")
		)
		(fp_line
			(start 0.299974 0.150114)
			(end -0.299974 0.150114)
			(stroke
				(width 0.1)
				(type default)
			)
			(layer "F.Fab")
		)
		(fp_line
			(start -0.299974 -0.150114)
			(end 0.299974 -0.150114)
			(stroke
				(width 0.1)
				(type default)
			)
			(layer "F.Fab")
		)
		(fp_line
			(start 0.299974 -0.150114)
			(end 0.299974 0.150114)
			(stroke
				(width 0.1)
				(type default)
			)
			(layer "F.Fab")
		)
		(pad "1" smd rect
			(at -0.2667 0 270)
			(size 0.3048 0.381)
			(layers "F.Cu" "F.Mask" "F.Paste")
			(net "P5E_CPU0_P0_TX_BUF_C_DP<11>")
		)
		(pad "2" smd rect
			(at 0.2667 0 270)
			(size 0.3048 0.381)
			(layers "F.Cu" "F.Mask" "F.Paste")
			(net "P5E_CPU0_P0_TX_BUF_DP<11>")
		)
	)
	(footprint ""
		(layer "F.Cu")
		(at 135.268462 -395.6304 -90)
		(property "Reference" "R895"
			(at 0 0 270)
			(layer "F.SilkS")
			(hide yes)
			(effects
				(font
					(size 1.27 1.27)
				)
			)
		)
		(property "Value" ""
			(at 0 0 270)
			(layer "F.Fab")
			(effects
				(font
					(size 1.27 1.27)
				)
			)
		)
		(duplicate_pad_numbers_are_jumpers no)
		(fp_line
			(start -0.32512 0.175006)
			(end -0.32512 -0.175006)
			(stroke
				(width 0.1)
				(type default)
			)
			(layer "F.Fab")
		)
		(fp_line
			(start 0.32512 0.175006)
			(end -0.32512 0.175006)
			(stroke
				(width 0.1)
				(type default)
			)
			(layer "F.Fab")
		)
		(fp_line
			(start -0.32512 -0.175006)
			(end 0.32512 -0.175006)
			(stroke
				(width 0.1)
				(type default)
			)
			(layer "F.Fab")
		)
		(fp_line
			(start 0.32512 -0.175006)
			(end 0.32512 0.175006)
			(stroke
				(width 0.1)
				(type default)
			)
			(layer "F.Fab")
		)
		(pad "1" smd rect
			(at -0.2667 0 270)
			(size 0.3048 0.381)
			(layers "F.Cu" "F.Mask" "F.Paste")
			(net "RST_RT_CPU1_P3_PERST_N")
		)
		(pad "2" smd rect
			(at 0.2667 0 90)
			(size 0.3048 0.381)
			(layers "F.Cu" "F.Mask" "F.Paste")
			(net "RST_RT_CPU1_P3_PERST_R_N")
		)
	)
	(footprint ""
		(layer "F.Cu")
		(at 50.927 -433.578 180)
		(property "Reference" "R3455"
			(at 0 0 180)
			(layer "F.SilkS")
			(hide yes)
			(effects
				(font
					(size 1.27 1.27)
				)
			)
		)
		(property "Value" ""
			(at 0 0 180)
			(layer "F.Fab")
			(effects
				(font
					(size 1.27 1.27)
				)
			)
		)
		(duplicate_pad_numbers_are_jumpers no)
		(fp_line
			(start 0.7874 0.4064)
			(end -0.7874 0.4064)
			(stroke
				(width 0.1524)
				(type default)
			)
			(layer "F.SilkS")
		)
		(fp_line
			(start 0.7874 -0.4064)
			(end 0.7874 0.4064)
			(stroke
				(width 0.1524)
				(type default)
			)
			(layer "F.SilkS")
		)
		(fp_line
			(start -0.7874 0.4064)
			(end -0.7874 -0.4064)
			(stroke
				(width 0.1524)
				(type default)
			)
			(layer "F.SilkS")
		)
		(fp_line
			(start -0.7874 -0.4064)
			(end 0.7874 -0.4064)
			(stroke
				(width 0.1524)
				(type default)
			)
			(layer "F.SilkS")
		)
		(fp_line
			(start 0.67945 0.3048)
			(end 0.120396 0.3048)
			(stroke
				(width 0.1)
				(type default)
			)
			(layer "F.Fab")
		)
		(fp_line
			(start 0.67945 -0.3048)
			(end 0.67945 0.3048)
			(stroke
				(width 0.1)
				(type default)
			)
			(layer "F.Fab")
		)
		(fp_line
			(start 0.12065 -0.2794)
			(end 0.12065 -0.3048)
			(stroke
				(width 0.1)
				(type default)
			)
			(layer "F.Fab")
		)
		(fp_line
			(start 0.12065 -0.3048)
			(end 0.67945 -0.3048)
			(stroke
				(width 0.1)
				(type default)
			)
			(layer "F.Fab")
		)
		(fp_line
			(start 0.120396 0.3048)
			(end 0.120396 0.2794)
			(stroke
				(width 0.1)
				(type default)
			)
			(layer "F.Fab")
		)
		(fp_line
			(start 0.120396 0.2794)
			(end -0.12065 0.2794)
			(stroke
				(width 0.1)
				(type default)
			)
			(layer "F.Fab")
		)
		(fp_line
			(start -0.12065 0.3048)
			(end -0.67945 0.3048)
			(stroke
				(width 0.1)
				(type default)
			)
			(layer "F.Fab")
		)
		(fp_line
			(start -0.12065 0.2794)
			(end -0.12065 0.3048)
			(stroke
				(width 0.1)
				(type default)
			)
			(layer "F.Fab")
		)
		(fp_line
			(start -0.12065 -0.2794)
			(end 0.12065 -0.2794)
			(stroke
				(width 0.1)
				(type default)
			)
			(layer "F.Fab")
		)
		(fp_line
			(start -0.12065 -0.305054)
			(end -0.12065 -0.2794)
			(stroke
				(width 0.1)
				(type default)
			)
			(layer "F.Fab")
		)
		(fp_line
			(start -0.67945 0.3048)
			(end -0.67945 -0.305054)
			(stroke
				(width 0.1)
				(type default)
			)
			(layer "F.Fab")
		)
		(fp_line
			(start -0.67945 -0.305054)
			(end -0.12065 -0.305054)
			(stroke
				(width 0.1)
				(type default)
			)
			(layer "F.Fab")
		)
		(pad "1" smd circle
			(at -0.40005 0 180)
			(size 0 0)
			(layers "F.Cu" "F.Mask" "F.Paste")
			(net "RST_PERST_2_SWB_BUF_R_N")
		)
		(pad "2" smd circle
			(at 0.40005 0 180)
			(size 0 0)
			(layers "F.Cu" "F.Mask" "F.Paste")
			(net "GND")
		)
	)
	(footprint ""
		(layer "F.Cu")
		(at 42.967402 -382.39446 180)
		(property "Reference" "C837"
			(at 0 0 180)
			(layer "F.SilkS")
			(hide yes)
			(effects
				(font
					(size 1.27 1.27)
				)
			)
		)
		(property "Value" ""
			(at 0 0 180)
			(layer "F.Fab")
			(effects
				(font
					(size 1.27 1.27)
				)
			)
		)
		(duplicate_pad_numbers_are_jumpers no)
		(fp_line
			(start 0.299974 0.150114)
			(end -0.299974 0.150114)
			(stroke
				(width 0.1)
				(type default)
			)
			(layer "F.Fab")
		)
		(fp_line
			(start 0.299974 -0.150114)
			(end 0.299974 0.150114)
			(stroke
				(width 0.1)
				(type default)
			)
			(layer "F.Fab")
		)
		(fp_line
			(start -0.299974 0.150114)
			(end -0.299974 -0.150114)
			(stroke
				(width 0.1)
				(type default)
			)
			(layer "F.Fab")
		)
		(fp_line
			(start -0.299974 -0.150114)
			(end 0.299974 -0.150114)
			(stroke
				(width 0.1)
				(type default)
			)
			(layer "F.Fab")
		)
		(pad "1" smd rect
			(at -0.2667 0 180)
			(size 0.3048 0.381)
			(layers "F.Cu" "F.Mask" "F.Paste")
			(net "P5E_CPU1_P0_TX_C_DP<0>")
		)
		(pad "2" smd rect
			(at 0.2667 0 180)
			(size 0.3048 0.381)
			(layers "F.Cu" "F.Mask" "F.Paste")
			(net "P5E_CPU1_P0_TX_DP<0>")
		)
	)
	(footprint ""
		(layer "F.Cu")
		(at 121.36374 -76.001626)
		(property "Reference" "PU6001"
			(at -4.776978 -4.383278 0)
			(unlocked yes)
			(layer "F.SilkS")
			(effects
				(font
					(size 0.7874 0.5842)
					(thickness 0.1524)
				)
				(justify left)
			)
		)
		(property "Value" ""
			(at 0 0 0)
			(layer "F.Fab")
			(effects
				(font
					(size 1.27 1.27)
				)
			)
		)
		(duplicate_pad_numbers_are_jumpers no)
		(fp_line
			(start -1.050036 -1.549908)
			(end -0.503936 -1.549908)
			(stroke
				(width 0.1524)
				(type default)
			)
			(layer "F.SilkS")
		)
		(fp_line
			(start -1.050036 -1.253998)
			(end -1.050036 -1.549908)
			(stroke
				(width 0.1524)
				(type default)
			)
			(layer "F.SilkS")
		)
		(fp_line
			(start -1.050036 1.549908)
			(end -1.050036 1.253998)
			(stroke
				(width 0.1524)
				(type default)
			)
			(layer "F.SilkS")
		)
		(fp_line
			(start -0.503936 1.549908)
			(end -1.050036 1.549908)
			(stroke
				(width 0.1524)
				(type default)
			)
			(layer "F.SilkS")
		)
		(fp_line
			(start 0.503936 -1.549908)
			(end 1.050036 -1.549908)
			(stroke
				(width 0.1524)
				(type default)
			)
			(layer "F.SilkS")
		)
		(fp_line
			(start 1.050036 -1.549908)
			(end 1.050036 -1.253998)
			(stroke
				(width 0.1524)
				(type default)
			)
			(layer "F.SilkS")
		)
		(fp_line
			(start 1.050036 1.253998)
			(end 1.050036 1.549908)
			(stroke
				(width 0.1524)
				(type default)
			)
			(layer "F.SilkS")
		)
		(fp_line
			(start 1.050036 1.549908)
			(end 0.503936 1.549908)
			(stroke
				(width 0.1524)
				(type default)
			)
			(layer "F.SilkS")
		)
		(fp_poly
			(pts
				(xy -1.394968 -1.542034) (xy -2.203196 -1.811528) (xy -1.664208 -2.350262)
			)
			(stroke
				(width 0)
				(type default)
			)
			(fill yes)
			(layer "F.SilkS")
		)
		(fp_line
			(start -1.050036 -1.549908)
			(end 1.050036 -1.549908)
			(stroke
				(width 0.1)
				(type default)
			)
			(layer "F.Fab")
		)
		(fp_line
			(start -1.050036 1.549908)
			(end -1.050036 -1.549908)
			(stroke
				(width 0.1)
				(type default)
			)
			(layer "F.Fab")
		)
		(fp_line
			(start 1.050036 -1.549908)
			(end 1.050036 1.549908)
			(stroke
				(width 0.1)
				(type default)
			)
			(layer "F.Fab")
		)
		(fp_line
			(start 1.050036 1.549908)
			(end -1.050036 1.549908)
			(stroke
				(width 0.1)
				(type default)
			)
			(layer "F.Fab")
		)
		(fp_poly
			(pts
				(xy -2.2352 -0.618998) (xy -2.2352 -1.380998) (xy -1.4732 -0.999998)
			)
			(stroke
				(width 0)
				(type default)
			)
			(fill yes)
			(layer "F.Fab")
		)
		(pad "1" smd circle
			(at -0.94996 -0.999998 270)
			(size 0 0)
			(layers "F.Cu" "F.Mask" "F.Paste")
			(net "GND")
		)
		(pad "2" smd rect
			(at -0.849884 -0.499872 90)
			(size 0.254 0.9144)
			(layers "F.Cu" "F.Mask" "F.Paste")
			(net "SW_P1V2_AUX_PH")
		)
		(pad "3" smd rect
			(at -0.649986 0 90)
			(size 0.254 1.3208)
			(layers "F.Cu" "F.Mask" "F.Paste")
			(net "SW_P12V_AUX_P1V2_AUX_FLT")
		)
		(pad "4" smd rect
			(at -0.849884 0.499872 90)
			(size 0.254 0.9144)
			(layers "F.Cu" "F.Mask" "F.Paste")
			(net "P1V2_AUX_CS")
		)
		(pad "5" smd circle
			(at -0.94996 0.999998 270)
			(size 0 0)
			(layers "F.Cu" "F.Mask" "F.Paste")
			(net "P1V2_AUX_ENABLE")
		)
		(pad "6" smd circle
			(at -0.249936 1.450086)
			(size 0 0)
			(layers "F.Cu" "F.Mask" "F.Paste")
			(net "P1V2_AUX_FB")
		)
		(pad "7" smd circle
			(at 0.249936 1.450086)
			(size 0 0)
			(layers "F.Cu" "F.Mask" "F.Paste")
			(net "GND")
		)
		(pad "8" smd circle
			(at 0.94996 0.999998 90)
			(size 0 0)
			(layers "F.Cu" "F.Mask" "F.Paste")
			(net "P1V2_AUX_REF")
		)
		(pad "9" smd rect
			(at 0.849884 0.499872 90)
			(size 0.254 0.9144)
			(layers "F.Cu" "F.Mask" "F.Paste")
			(net "PWRGD_P1V2_AUX")
		)
		(pad "10" smd rect
			(at 0.849884 0 90)
			(size 0.254 0.9144)
			(layers "F.Cu" "F.Mask" "F.Paste")
			(net "SW_P1V2_AUX_BT")
		)
		(pad "11" smd rect
			(at 0.849884 -0.499872 90)
			(size 0.254 0.9144)
			(layers "F.Cu" "F.Mask" "F.Paste")
			(net "SW_P1V2_AUX_PH")
		)
		(pad "12" smd circle
			(at 0.94996 -0.999998 90)
			(size 0 0)
			(layers "F.Cu" "F.Mask" "F.Paste")
			(net "P1V2_AUX_MODE")
		)
		(pad "13" smd circle
			(at 0.249936 -1.450086 180)
			(size 0 0)
			(layers "F.Cu" "F.Mask" "F.Paste")
			(net "P1V2_AUX_VCC")
		)
		(pad "14" smd circle
			(at -0.249936 -1.450086 180)
			(size 0 0)
			(layers "F.Cu" "F.Mask" "F.Paste")
			(net "GND")
		)
	)
	(footprint ""
		(layer "F.Cu")
		(at 355.506782 -413.046418)
		(property "Reference" "R4153"
			(at 0 0 0)
			(layer "F.SilkS")
			(hide yes)
			(effects
				(font
					(size 1.27 1.27)
				)
			)
		)
		(property "Value" ""
			(at 0 0 0)
			(layer "F.Fab")
			(effects
				(font
					(size 1.27 1.27)
				)
			)
		)
		(duplicate_pad_numbers_are_jumpers no)
		(fp_line
			(start -0.7874 -0.4064)
			(end 0.7874 -0.4064)
			(stroke
				(width 0.1524)
				(type default)
			)
			(layer "F.SilkS")
		)
		(fp_line
			(start -0.7874 0.4064)
			(end -0.7874 -0.4064)
			(stroke
				(width 0.1524)
				(type default)
			)
			(layer "F.SilkS")
		)
		(fp_line
			(start 0.7874 -0.4064)
			(end 0.7874 0.4064)
			(stroke
				(width 0.1524)
				(type default)
			)
			(layer "F.SilkS")
		)
		(fp_line
			(start 0.7874 0.4064)
			(end -0.7874 0.4064)
			(stroke
				(width 0.1524)
				(type default)
			)
			(layer "F.SilkS")
		)
		(fp_line
			(start -0.67945 -0.305054)
			(end -0.12065 -0.305054)
			(stroke
				(width 0.1)
				(type default)
			)
			(layer "F.Fab")
		)
		(fp_line
			(start -0.67945 0.3048)
			(end -0.67945 -0.305054)
			(stroke
				(width 0.1)
				(type default)
			)
			(layer "F.Fab")
		)
		(fp_line
			(start -0.12065 -0.305054)
			(end -0.12065 -0.2794)
			(stroke
				(width 0.1)
				(type default)
			)
			(layer "F.Fab")
		)
		(fp_line
			(start -0.12065 -0.2794)
			(end 0.12065 -0.2794)
			(stroke
				(width 0.1)
				(type default)
			)
			(layer "F.Fab")
		)
		(fp_line
			(start -0.12065 0.2794)
			(end -0.12065 0.3048)
			(stroke
				(width 0.1)
				(type default)
			)
			(layer "F.Fab")
		)
		(fp_line
			(start -0.12065 0.3048)
			(end -0.67945 0.3048)
			(stroke
				(width 0.1)
				(type default)
			)
			(layer "F.Fab")
		)
		(fp_line
			(start 0.120396 0.2794)
			(end -0.12065 0.2794)
			(stroke
				(width 0.1)
				(type default)
			)
			(layer "F.Fab")
		)
		(fp_line
			(start 0.120396 0.3048)
			(end 0.120396 0.2794)
			(stroke
				(width 0.1)
				(type default)
			)
			(layer "F.Fab")
		)
		(fp_line
			(start 0.12065 -0.3048)
			(end 0.67945 -0.3048)
			(stroke
				(width 0.1)
				(type default)
			)
			(layer "F.Fab")
		)
		(fp_line
			(start 0.12065 -0.2794)
			(end 0.12065 -0.3048)
			(stroke
				(width 0.1)
				(type default)
			)
			(layer "F.Fab")
		)
		(fp_line
			(start 0.67945 -0.3048)
			(end 0.67945 0.3048)
			(stroke
				(width 0.1)
				(type default)
			)
			(layer "F.Fab")
		)
		(fp_line
			(start 0.67945 0.3048)
			(end 0.120396 0.3048)
			(stroke
				(width 0.1)
				(type default)
			)
			(layer "F.Fab")
		)
		(pad "1" smd circle
			(at -0.40005 0)
			(size 0 0)
			(layers "F.Cu" "F.Mask" "F.Paste")
			(net "P3V3_AUX")
		)
		(pad "2" smd circle
			(at 0.40005 0)
			(size 0 0)
			(layers "F.Cu" "F.Mask" "F.Paste")
			(net "PRSNT_CABLE_GPU_A1_N")
		)
	)
)
